FILE_TYPE = CONNECTIVITY;
{Allegro Design Entry HDL 17.2-2016 S081 (4005846) 1/11/2022}
"PAGE_NUMBER" = 15;
0"NC";
1"M_F_CPU0_SA_DQ<31:0>";
2"M_F_CPU0_SB_DQ<31:0>";
3"M_F_CPU0_SA_CB<7:0>";
4"M_F_CPU0_SB_CB<7:0>";
5"M_F_CPU0_SA_DQS_DP<9:0>";
6"M_F_CPU0_SB_DQS_DP<9:0>";
7"M_F_CPU0_SA_CA<6:0>";
8"M_F_CPU0_SB_CA<6:0>";
9"M_F_CPU0_SA_DQS_DN<9:0>";
10"M_F_CPU0_SB_DQS_DN<9:0>";
11"M_F_CPU0_ALERT_N";
12"TP_M_F_CPU0_SA_TEST39F";
13"M_F_CPU0_ALERT_R_N";
14"M_F_CPU0_CLK_DP<0>";
15"M_F_CPU0_CLK_DN<0>";
16"M_F_CPU0_SA_CS_N<0>";
17"M_F_CPU0_SA_CS_N<1>";
18"M_F_CPU0_SB_RSP<0>";
19"M_F_CPU0_SA_RSP<0>";
20"M_F_CPU0_SA_PAR";
21"M_F_CPU0_SB_CS_N<0>";
22"M_F_CPU0_SB_CS_N<1>";
23"M_F_CPU0_SB_PAR";
24"M_F_CPU0_RESET_N";
25"M_F_CPU0_SB_DQS_DP<9>";
26"M_F_CPU0_SB_CA<6>";
27"M_F_CPU0_SA_CA<6>";
28"M_F_CPU0_SB_CA<5>";
29"M_F_CPU0_SA_CA<5>";
30"M_F_CPU0_SB_CA<4>";
31"M_F_CPU0_SA_CA<4>";
32"M_F_CPU0_SB_CA<3>";
33"M_F_CPU0_SA_CA<3>";
34"M_F_CPU0_SB_CA<2>";
35"M_F_CPU0_SA_CA<2>";
36"M_F_CPU0_SB_CA<1>";
37"M_F_CPU0_SA_CA<1>";
38"M_F_CPU0_SB_CA<0>";
39"M_F_CPU0_SA_CA<0>";
40"M_F_CPU0_SB_DQS_DN<9>";
41"M_F_CPU0_SB_DQS_DN<8>";
42"M_F_CPU0_SB_DQS_DP<1>";
43"M_F_CPU0_SB_DQS_DN<5>";
44"M_F_CPU0_SB_DQS_DP<0>";
45"M_F_CPU0_SB_DQS_DN<4>";
46"M_F_CPU0_SA_DQS_DN<9>";
47"M_F_CPU0_SB_DQS_DN<3>";
48"M_F_CPU0_SB_DQS_DN<2>";
49"M_F_CPU0_SB_DQS_DN<1>";
50"M_F_CPU0_SB_DQS_DN<0>";
51"M_F_CPU0_SB_DQS_DP<8>";
52"M_F_CPU0_SB_DQS_DP<7>";
53"M_F_CPU0_SB_DQS_DP<6>";
54"M_F_CPU0_SB_DQS_DP<5>";
55"M_F_CPU0_SB_DQS_DP<4>";
56"M_F_CPU0_SA_DQS_DP<9>";
57"M_F_CPU0_SB_DQS_DP<3>";
58"M_F_CPU0_SB_DQS_DN<7>";
59"M_F_CPU0_SB_DQS_DP<2>";
60"M_F_CPU0_SB_DQS_DN<6>";
61"M_F_CPU0_SA_DQS_DP<7>";
62"M_F_CPU0_SA_DQS_DP<6>";
63"M_F_CPU0_SA_DQS_DP<5>";
64"M_F_CPU0_SA_DQS_DP<4>";
65"M_F_CPU0_SA_DQS_DN<8>";
66"M_F_CPU0_SA_DQS_DP<3>";
67"M_F_CPU0_SA_DQS_DN<7>";
68"M_F_CPU0_SA_DQS_DP<2>";
69"M_F_CPU0_SA_DQS_DN<6>";
70"M_F_CPU0_SA_DQS_DP<1>";
71"M_F_CPU0_SA_DQS_DN<5>";
72"M_F_CPU0_SA_DQS_DP<0>";
73"M_F_CPU0_SA_DQS_DN<4>";
74"M_F_CPU0_SA_DQS_DN<3>";
75"M_F_CPU0_SA_DQS_DN<2>";
76"M_F_CPU0_SA_DQS_DN<1>";
77"M_F_CPU0_SA_DQS_DN<0>";
78"M_F_CPU0_SA_DQS_DP<8>";
79"M_F_CPU0_SB_CB<7>";
80"M_F_CPU0_SB_CB<6>";
81"M_F_CPU0_SB_CB<5>";
82"M_F_CPU0_SB_CB<4>";
83"M_F_CPU0_SB_CB<3>";
84"M_F_CPU0_SB_CB<2>";
85"M_F_CPU0_SA_CB<7>";
86"M_F_CPU0_SB_CB<1>";
87"M_F_CPU0_SB_CB<0>";
88"M_F_CPU0_SB_DQ<29>";
89"M_F_CPU0_SB_DQ<28>";
90"M_F_CPU0_SB_DQ<27>";
91"M_F_CPU0_SB_DQ<26>";
92"M_F_CPU0_SB_DQ<25>";
93"M_F_CPU0_SB_DQ<24>";
94"M_F_CPU0_SB_DQ<23>";
95"M_F_CPU0_SB_DQ<22>";
96"M_F_CPU0_SB_DQ<21>";
97"M_F_CPU0_SA_CB<6>";
98"M_F_CPU0_SB_DQ<31>";
99"M_F_CPU0_SA_CB<5>";
100"M_F_CPU0_SB_DQ<30>";
101"M_F_CPU0_SA_CB<4>";
102"M_F_CPU0_SA_CB<3>";
103"M_F_CPU0_SA_CB<2>";
104"M_F_CPU0_SA_CB<1>";
105"M_F_CPU0_SA_CB<0>";
106"M_F_CPU0_SB_DQ<6>";
107"M_F_CPU0_SB_DQ<18>";
108"M_F_CPU0_SB_DQ<5>";
109"M_F_CPU0_SB_DQ<17>";
110"M_F_CPU0_SB_DQ<4>";
111"M_F_CPU0_SB_DQ<16>";
112"M_F_CPU0_SB_DQ<3>";
113"M_F_CPU0_SB_DQ<15>";
114"M_F_CPU0_SB_DQ<2>";
115"M_F_CPU0_SB_DQ<14>";
116"M_F_CPU0_SB_DQ<13>";
117"M_F_CPU0_SB_DQ<12>";
118"M_F_CPU0_SB_DQ<11>";
119"M_F_CPU0_SB_DQ<10>";
120"M_F_CPU0_SB_DQ<20>";
121"M_F_CPU0_SB_DQ<9>";
122"M_F_CPU0_SB_DQ<8>";
123"M_F_CPU0_SB_DQ<7>";
124"M_F_CPU0_SB_DQ<19>";
125"M_F_CPU0_SA_DQ<19>";
126"M_F_CPU0_SB_DQ<1>";
127"M_F_CPU0_SA_DQ<18>";
128"M_F_CPU0_SA_DQ<29>";
129"M_F_CPU0_SB_DQ<0>";
130"M_F_CPU0_SA_DQ<17>";
131"M_F_CPU0_SA_DQ<28>";
132"M_F_CPU0_SA_DQ<16>";
133"M_F_CPU0_SA_DQ<27>";
134"M_F_CPU0_SA_DQ<26>";
135"M_F_CPU0_SA_DQ<25>";
136"M_F_CPU0_SA_DQ<24>";
137"M_F_CPU0_SA_DQ<23>";
138"M_F_CPU0_SA_DQ<22>";
139"M_F_CPU0_SA_DQ<21>";
140"M_F_CPU0_SA_DQ<20>";
141"M_F_CPU0_SA_DQ<31>";
142"M_F_CPU0_SA_DQ<30>";
143"M_F_CPU0_SA_DQ<7>";
144"M_F_CPU0_SA_DQ<6>";
145"M_F_CPU0_SA_DQ<5>";
146"M_F_CPU0_SA_DQ<4>";
147"M_F_CPU0_SA_DQ<3>";
148"M_F_CPU0_SA_DQ<2>";
149"M_F_CPU0_SA_DQ<1>";
150"M_F_CPU0_SA_DQ<0>";
151"M_F_CPU0_SA_DQ<15>";
152"M_F_CPU0_SA_DQ<14>";
153"M_F_CPU0_SA_DQ<13>";
154"M_F_CPU0_SA_DQ<12>";
155"M_F_CPU0_SA_DQ<11>";
156"M_F_CPU0_SA_DQ<10>";
157"M_F_CPU0_SA_DQ<9>";
158"M_F_CPU0_SA_DQ<8>";
%"GENOA_SP5"
"6","(-4650,3600)","0","pure_quanta","I159";
;
LOCATION"U25"
$SEC"6"
CDS_SEC"6"
PART_TYPE"SMLF"
MATERIAL"IO"
VALUE"SOCKET6096_13568-001"
PART_NUMBER"DGA^6000030"
CDS_LIB"pure_quanta"
CDS_LMAN_SYM_OUTLINE"-650,2525,650,-2525"
NEEDS_NO_SIZE"TRUE";
"TEST39F"
$PN"BF65"12;
"MF1_CLK_L"
$PN"BG67"0;
"MF1_CLK_H"
$PN"BF67"0;
"MF0_CLK_L"
$PN"BD67"15;
"MF0_CLK_H"
$PN"BC67"14;
"MFB_DQS_H9"
$PN"BV67"25;
"MFB_PAR"
$PN"BL67"23;
"MFA_PAR"
$PN"BC66"20;
"MFA0_CS_L0"
$PN"AV67"16;
"MFA_DATA7"
$PN"L66"143;
"MFA_DQS_H7"
$PN"AA66"61;
"MFB_DATA6"
$PN"CG67"106;
"MFB_DATA18"
$PN"CR67"107;
"MFB_DATA29"
$PN"DE66"88;
"MFB_DQS_H1"
$PN"CK67"42;
"MFB_DQS_L5"
$PN"CE66"43;
"MFA_DATA6"
$PN"K67"144;
"MFA_DQS_H6"
$PN"R66"62;
"MFB1_RSP_L"
$PN"BR67"0;
"MFB_DATA5"
$PN"CG66"108;
"MFB_DATA17"
$PN"CR66"109;
"MFB_DATA28"
$PN"DD67"89;
"MFB_DQS_H0"
$PN"CD67"44;
"MFB_DQS_L4"
$PN"BW66"45;
"MFA_DATA5"
$PN"K65"145;
"MFA_DQS_H5"
$PN"J66"63;
"MFA_DQS_L9"
$PN"AM65"46;
"MFB0_RSP_L"
$PN"BP67"18;
"MFB_CHECK7"
$PN"BV65"79;
"MFB_DATA4"
$PN"CF67"110;
"MFB_DATA16"
$PN"CP67"111;
"MFB_DATA27"
$PN"DB65"90;
"MFB_DQS_L3"
$PN"DC67"47;
"MFA_DATA4"
$PN"J67"146;
"MFA_DQS_H4"
$PN"AL67"64;
"MFA_DQS_L8"
$PN"AF65"65;
"MFB_CHECK6"
$PN"BU67"80;
"MFB_DATA3"
$PN"CD65"112;
"MFB_DATA15"
$PN"CP65"113;
"MFB_DATA26"
$PN"DA67"91;
"MFB_DQS_L2"
$PN"CU67"48;
"MFA_DATA3"
$PN"G66"147;
"MFA_DQS_H3"
$PN"AE67"66;
"MFA_DQS_L7"
$PN"Y65"67;
"MFB_CHECK5"
$PN"BU66"81;
"MFB_DATA2"
$PN"CC67"114;
"MFB_DATA14"
$PN"CN67"115;
"MFB_DATA25"
$PN"DA66"92;
"MFB_DQS_L1"
$PN"CL67"49;
"MFA_DATA2"
$PN"F67"148;
"MFA_DATA19"
$PN"W66"125;
"MFA_DQS_H2"
$PN"W67"68;
"MFA_DQS_L6"
$PN"P65"69;
"MFB_CA6"
$PN"BK67"26;
"MFB_CHECK4"
$PN"BT67"82;
"MFB_DATA1"
$PN"CC66"126;
"MFB_DATA13"
$PN"CN66"116;
"MFB_DATA24"
$PN"CY67"93;
"MFB_DQS_L0"
$PN"CE67"50;
"MFA_CA6"
$PN"BB65"27;
"MFA_DATA1"
$PN"F65"149;
"MFA_DATA18"
$PN"V67"127;
"MFA_DATA29"
$PN"AH65"128;
"MFA_DQS_H1"
$PN"N67"70;
"MFA_DQS_L5"
$PN"H65"71;
"MFB_CA5"
$PN"BK65"28;
"MFB_CHECK3"
$PN"CB65"83;
"MFB_DATA0"
$PN"CB67"129;
"MFB_DATA12"
$PN"CM67"117;
"MFB_DATA23"
$PN"CY65"94;
"MFA1_RSP_L"
$PN"BP65"0;
"MFA_CA5"
$PN"BB67"29;
"MFA_DATA0"
$PN"E67"150;
"MFA_DATA17"
$PN"V65"130;
"MFA_DATA28"
$PN"AG67"131;
"MFA_DQS_H0"
$PN"G67"72;
"MFA_DQS_L4"
$PN"AM67"73;
"MFB_CA4"
$PN"BJ66"30;
"MFB_CHECK2"
$PN"CA67"84;
"MFB_DATA11"
$PN"CK65"118;
"MFB_DATA22"
$PN"CW67"95;
"MFA0_RSP_L"
$PN"BN66"19;
"MFA_CA4"
$PN"BA67"31;
"MFA_CHECK7"
$PN"AR66"85;
"MFA_DATA16"
$PN"U67"132;
"MFA_DATA27"
$PN"AE66"133;
"MFA_DQS_L3"
$PN"AF67"74;
"MFB_CA3"
$PN"BJ67"32;
"MFB_CHECK1"
$PN"CA66"86;
"MFB_DATA10"
$PN"CJ67"119;
"MFB_DATA21"
$PN"CW66"96;
"MFA_CA3"
$PN"BA66"33;
"MFA_CHECK6"
$PN"AP67"97;
"MFA_DATA15"
$PN"U66"151;
"MFA_DATA26"
$PN"AD67"134;
"MFA_DQS_L2"
$PN"Y67"75;
"MFB1_CS_L1"
$PN"BM67"0;
"MFB_CA2"
$PN"BH67"34;
"MFB_CHECK0"
$PN"BY67"87;
"MFB_DATA20"
$PN"CV67"120;
"MFB_DATA31"
$PN"DF67"98;
"MFA_CA2"
$PN"AY65"35;
"MFA_CHECK5"
$PN"AP65"99;
"MFA_DATA14"
$PN"T67"152;
"MFA_DATA25"
$PN"AD65"135;
"MFA_DQS_L1"
$PN"P67"76;
"MFB0_CS_L1"
$PN"BN67"22;
"MFB1_CS_L0"
$PN"BL66"0;
"MFB_CA1"
$PN"BH65"36;
"MFB_DATA30"
$PN"DE67"100;
"MFB_DQS_H8"
$PN"DD65"51;
"MFA_CA1"
$PN"AY67"37;
"MFA_CHECK4"
$PN"AN67"101;
"MFA_DATA13"
$PN"T65"153;
"MFA_DATA24"
$PN"AC67"136;
"MFA_DQS_L0"
$PN"H67"77;
"MFB0_CS_L0"
$PN"BM65"21;
"MFB_CA0"
$PN"BG66"38;
"MFB_DQS_H7"
$PN"CV65"52;
"MFA_CA0"
$PN"AW67"39;
"MFA_CHECK3"
$PN"AL66"102;
"MFA_DATA12"
$PN"R67"154;
"MFA_DATA23"
$PN"AC66"137;
"MFB_DQS_H6"
$PN"CM65"53;
"MFA_CHECK2"
$PN"AK67"103;
"MFA_DATA11"
$PN"N66"155;
"MFA_DATA22"
$PN"AB67"138;
"MFB_DQS_H5"
$PN"CF65"54;
"MFB_DQS_L9"
$PN"BW67"40;
"MFA_CHECK1"
$PN"AK65"104;
"MFA_DATA10"
$PN"M67"156;
"MFA_DATA21"
$PN"AB65"139;
"MFB_DATA9"
$PN"CJ66"121;
"MFB_DQS_H4"
$PN"BY65"55;
"MFB_DQS_L8"
$PN"DC66"41;
"MFA1_CS_L1"
$PN"AV65"0;
"MFA_CHECK0"
$PN"AJ67"105;
"MFA_DATA9"
$PN"M65"157;
"MFA_DATA20"
$PN"AA67"140;
"MFA_DATA31"
$PN"AJ66"141;
"MFA_DQS_H9"
$PN"AN66"56;
"MFB_DATA8"
$PN"CH67"122;
"MFB_DQS_H3"
$PN"DB67"57;
"MFB_DQS_L7"
$PN"CU66"58;
"MFA0_CS_L1"
$PN"AW66"17;
"MFA1_CS_L0"
$PN"AU67"0;
"MFA_DATA8"
$PN"L67"158;
"MFA_DATA30"
$PN"AH67"142;
"MFA_DQS_H8"
$PN"AG66"78;
"MFB_DATA7"
$PN"CH65"123;
"MFB_DATA19"
$PN"CT65"124;
"MFB_DQS_H2"
$PN"CT67"59;
"MFB_DQS_L6"
$PN"CL66"60;
"MF_RESET_L"
$PN"AU66"24;
"MF_ALERT_L"
$PN"AT65"13;
%"TAP"
"1","(-3375,5975)","0","mstr_standard","I162";
;
CDS_LIB"mstr_standard"
BODY_TYPE"PLUMBING"
HDL_TAP"TRUE";
"B \NAC \NWC"1;
"S \NAC"
BN"0"150;
%"TAP"
"1","(-3375,5925)","0","mstr_standard","I163";
;
CDS_LIB"mstr_standard"
BODY_TYPE"PLUMBING"
HDL_TAP"TRUE";
"B \NAC \NWC"1;
"S \NAC"
BN"1"149;
%"TAP"
"1","(-3375,5775)","0","mstr_standard","I164";
;
CDS_LIB"mstr_standard"
BODY_TYPE"PLUMBING"
HDL_TAP"TRUE";
"B \NAC \NWC"1;
"S \NAC"
BN"4"146;
%"TAP"
"1","(-3375,5825)","0","mstr_standard","I165";
;
CDS_LIB"mstr_standard"
BODY_TYPE"PLUMBING"
HDL_TAP"TRUE";
"B \NAC \NWC"1;
"S \NAC"
BN"3"147;
%"TAP"
"1","(-3375,5875)","0","mstr_standard","I166";
;
CDS_LIB"mstr_standard"
BODY_TYPE"PLUMBING"
HDL_TAP"TRUE";
"B \NAC \NWC"1;
"S \NAC"
BN"2"148;
%"TAP"
"1","(-3375,5675)","0","mstr_standard","I167";
;
CDS_LIB"mstr_standard"
BODY_TYPE"PLUMBING"
HDL_TAP"TRUE";
"B \NAC \NWC"1;
"S \NAC"
BN"6"144;
%"TAP"
"1","(-3375,5725)","0","mstr_standard","I168";
;
CDS_LIB"mstr_standard"
BODY_TYPE"PLUMBING"
HDL_TAP"TRUE";
"B \NAC \NWC"1;
"S \NAC"
BN"5"145;
%"TAP"
"1","(-3375,5525)","0","mstr_standard","I169";
;
CDS_LIB"mstr_standard"
BODY_TYPE"PLUMBING"
HDL_TAP"TRUE";
"B \NAC \NWC"1;
"S \NAC"
BN"8"158;
%"TAP"
"1","(-3375,5625)","0","mstr_standard","I170";
;
CDS_LIB"mstr_standard"
BODY_TYPE"PLUMBING"
HDL_TAP"TRUE";
"B \NAC \NWC"1;
"S \NAC"
BN"7"143;
%"TAP"
"1","(-3375,5475)","0","mstr_standard","I171";
;
CDS_LIB"mstr_standard"
BODY_TYPE"PLUMBING"
HDL_TAP"TRUE";
"B \NAC \NWC"1;
"S \NAC"
BN"9"157;
%"TAP"
"1","(-3375,5425)","0","mstr_standard","I172";
;
CDS_LIB"mstr_standard"
BODY_TYPE"PLUMBING"
HDL_TAP"TRUE";
"B \NAC \NWC"1;
"S \NAC"
BN"10"156;
%"TAP"
"1","(-3375,5275)","0","mstr_standard","I173";
;
CDS_LIB"mstr_standard"
BODY_TYPE"PLUMBING"
HDL_TAP"TRUE";
"B \NAC \NWC"1;
"S \NAC"
BN"13"153;
%"TAP"
"1","(-3375,5325)","0","mstr_standard","I174";
;
CDS_LIB"mstr_standard"
BODY_TYPE"PLUMBING"
HDL_TAP"TRUE";
"B \NAC \NWC"1;
"S \NAC"
BN"12"154;
%"TAP"
"1","(-3375,5375)","0","mstr_standard","I175";
;
CDS_LIB"mstr_standard"
BODY_TYPE"PLUMBING"
HDL_TAP"TRUE";
"B \NAC \NWC"1;
"S \NAC"
BN"11"155;
%"TAP"
"1","(-3375,5175)","0","mstr_standard","I176";
;
CDS_LIB"mstr_standard"
BODY_TYPE"PLUMBING"
HDL_TAP"TRUE";
"B \NAC \NWC"1;
"S \NAC"
BN"15"151;
%"TAP"
"1","(-3375,5225)","0","mstr_standard","I177";
;
CDS_LIB"mstr_standard"
BODY_TYPE"PLUMBING"
HDL_TAP"TRUE";
"B \NAC \NWC"1;
"S \NAC"
BN"14"152;
%"TAP"
"1","(-3375,5025)","0","mstr_standard","I178";
;
CDS_LIB"mstr_standard"
BODY_TYPE"PLUMBING"
HDL_TAP"TRUE";
"B \NAC \NWC"1;
"S \NAC"
BN"17"130;
%"TAP"
"1","(-3375,5075)","0","mstr_standard","I179";
;
CDS_LIB"mstr_standard"
BODY_TYPE"PLUMBING"
HDL_TAP"TRUE";
"B \NAC \NWC"1;
"S \NAC"
BN"16"132;
%"TAP"
"1","(-3375,4875)","0","mstr_standard","I180";
;
CDS_LIB"mstr_standard"
BODY_TYPE"PLUMBING"
HDL_TAP"TRUE";
"B \NAC \NWC"1;
"S \NAC"
BN"20"140;
%"TAP"
"1","(-3375,4925)","0","mstr_standard","I181";
;
CDS_LIB"mstr_standard"
BODY_TYPE"PLUMBING"
HDL_TAP"TRUE";
"B \NAC \NWC"1;
"S \NAC"
BN"19"125;
%"TAP"
"1","(-3375,4975)","0","mstr_standard","I182";
;
CDS_LIB"mstr_standard"
BODY_TYPE"PLUMBING"
HDL_TAP"TRUE";
"B \NAC \NWC"1;
"S \NAC"
BN"18"127;
%"TAP"
"1","(-3375,4775)","0","mstr_standard","I183";
;
CDS_LIB"mstr_standard"
BODY_TYPE"PLUMBING"
HDL_TAP"TRUE";
"B \NAC \NWC"1;
"S \NAC"
BN"22"138;
%"TAP"
"1","(-3375,4825)","0","mstr_standard","I184";
;
CDS_LIB"mstr_standard"
BODY_TYPE"PLUMBING"
HDL_TAP"TRUE";
"B \NAC \NWC"1;
"S \NAC"
BN"21"139;
%"TAP"
"1","(-3375,4725)","0","mstr_standard","I185";
;
CDS_LIB"mstr_standard"
BODY_TYPE"PLUMBING"
HDL_TAP"TRUE";
"B \NAC \NWC"1;
"S \NAC"
BN"23"137;
%"TAP"
"1","(-3375,4625)","0","mstr_standard","I186";
;
CDS_LIB"mstr_standard"
BODY_TYPE"PLUMBING"
HDL_TAP"TRUE";
"B \NAC \NWC"1;
"S \NAC"
BN"24"136;
%"TAP"
"1","(-3375,4575)","0","mstr_standard","I187";
;
CDS_LIB"mstr_standard"
BODY_TYPE"PLUMBING"
HDL_TAP"TRUE";
"B \NAC \NWC"1;
"S \NAC"
BN"25"135;
%"TAP"
"1","(-3375,4525)","0","mstr_standard","I188";
;
CDS_LIB"mstr_standard"
BODY_TYPE"PLUMBING"
HDL_TAP"TRUE";
"B \NAC \NWC"1;
"S \NAC"
BN"26"134;
%"TAP"
"1","(-3375,4375)","0","mstr_standard","I189";
;
CDS_LIB"mstr_standard"
BODY_TYPE"PLUMBING"
HDL_TAP"TRUE";
"B \NAC \NWC"1;
"S \NAC"
BN"29"128;
%"TAP"
"1","(-3375,4425)","0","mstr_standard","I190";
;
CDS_LIB"mstr_standard"
BODY_TYPE"PLUMBING"
HDL_TAP"TRUE";
"B \NAC \NWC"1;
"S \NAC"
BN"28"131;
%"TAP"
"1","(-3375,4475)","0","mstr_standard","I191";
;
CDS_LIB"mstr_standard"
BODY_TYPE"PLUMBING"
HDL_TAP"TRUE";
"B \NAC \NWC"1;
"S \NAC"
BN"27"133;
%"TAP"
"1","(-3375,4275)","0","mstr_standard","I192";
;
CDS_LIB"mstr_standard"
BODY_TYPE"PLUMBING"
HDL_TAP"TRUE";
"B \NAC \NWC"1;
"S \NAC"
BN"31"141;
%"TAP"
"1","(-3375,4325)","0","mstr_standard","I193";
;
CDS_LIB"mstr_standard"
BODY_TYPE"PLUMBING"
HDL_TAP"TRUE";
"B \NAC \NWC"1;
"S \NAC"
BN"30"142;
%"TAP"
"1","(-3375,4125)","0","mstr_standard","I194";
;
CDS_LIB"mstr_standard"
BODY_TYPE"PLUMBING"
HDL_TAP"TRUE";
"B \NAC \NWC"2;
"S \NAC"
BN"1"126;
%"TAP"
"1","(-3375,4175)","0","mstr_standard","I195";
;
CDS_LIB"mstr_standard"
BODY_TYPE"PLUMBING"
HDL_TAP"TRUE";
"B \NAC \NWC"2;
"S \NAC"
BN"0"129;
%"TAP"
"1","(-3375,3975)","0","mstr_standard","I197";
;
CDS_LIB"mstr_standard"
BODY_TYPE"PLUMBING"
HDL_TAP"TRUE";
"B \NAC \NWC"2;
"S \NAC"
BN"4"110;
%"TAP"
"1","(-3375,4025)","0","mstr_standard","I198";
;
CDS_LIB"mstr_standard"
BODY_TYPE"PLUMBING"
HDL_TAP"TRUE";
"B \NAC \NWC"2;
"S \NAC"
BN"3"112;
%"TAP"
"1","(-3375,4075)","0","mstr_standard","I199";
;
CDS_LIB"mstr_standard"
BODY_TYPE"PLUMBING"
HDL_TAP"TRUE";
"B \NAC \NWC"2;
"S \NAC"
BN"2"114;
%"TAP"
"1","(-3375,3875)","0","mstr_standard","I200";
;
CDS_LIB"mstr_standard"
BODY_TYPE"PLUMBING"
HDL_TAP"TRUE";
"B \NAC \NWC"2;
"S \NAC"
BN"6"106;
%"TAP"
"1","(-3375,3925)","0","mstr_standard","I201";
;
CDS_LIB"mstr_standard"
BODY_TYPE"PLUMBING"
HDL_TAP"TRUE";
"B \NAC \NWC"2;
"S \NAC"
BN"5"108;
%"TAP"
"1","(-3375,3725)","0","mstr_standard","I202";
;
CDS_LIB"mstr_standard"
BODY_TYPE"PLUMBING"
HDL_TAP"TRUE";
"B \NAC \NWC"2;
"S \NAC"
BN"8"122;
%"TAP"
"1","(-3375,3825)","0","mstr_standard","I203";
;
CDS_LIB"mstr_standard"
BODY_TYPE"PLUMBING"
HDL_TAP"TRUE";
"B \NAC \NWC"2;
"S \NAC"
BN"7"123;
%"TAP"
"1","(-3375,3625)","0","mstr_standard","I204";
;
CDS_LIB"mstr_standard"
BODY_TYPE"PLUMBING"
HDL_TAP"TRUE";
"B \NAC \NWC"2;
"S \NAC"
BN"10"119;
%"TAP"
"1","(-3375,3675)","0","mstr_standard","I205";
;
CDS_LIB"mstr_standard"
BODY_TYPE"PLUMBING"
HDL_TAP"TRUE";
"B \NAC \NWC"2;
"S \NAC"
BN"9"121;
%"TAP"
"1","(-3375,3475)","0","mstr_standard","I206";
;
CDS_LIB"mstr_standard"
BODY_TYPE"PLUMBING"
HDL_TAP"TRUE";
"B \NAC \NWC"2;
"S \NAC"
BN"13"116;
%"TAP"
"1","(-3375,3525)","0","mstr_standard","I207";
;
CDS_LIB"mstr_standard"
BODY_TYPE"PLUMBING"
HDL_TAP"TRUE";
"B \NAC \NWC"2;
"S \NAC"
BN"12"117;
%"TAP"
"1","(-3375,3575)","0","mstr_standard","I208";
;
CDS_LIB"mstr_standard"
BODY_TYPE"PLUMBING"
HDL_TAP"TRUE";
"B \NAC \NWC"2;
"S \NAC"
BN"11"118;
%"TAP"
"1","(-3375,3425)","0","mstr_standard","I209";
;
CDS_LIB"mstr_standard"
BODY_TYPE"PLUMBING"
HDL_TAP"TRUE";
"B \NAC \NWC"2;
"S \NAC"
BN"14"115;
%"TAP"
"1","(-3375,3375)","0","mstr_standard","I210";
;
CDS_LIB"mstr_standard"
BODY_TYPE"PLUMBING"
HDL_TAP"TRUE";
"B \NAC \NWC"2;
"S \NAC"
BN"15"113;
%"TAP"
"1","(-3375,3275)","0","mstr_standard","I211";
;
CDS_LIB"mstr_standard"
BODY_TYPE"PLUMBING"
HDL_TAP"TRUE";
"B \NAC \NWC"2;
"S \NAC"
BN"16"111;
%"TAP"
"1","(-3375,3225)","0","mstr_standard","I212";
;
CDS_LIB"mstr_standard"
BODY_TYPE"PLUMBING"
HDL_TAP"TRUE";
"B \NAC \NWC"2;
"S \NAC"
BN"17"109;
%"TAP"
"1","(-3375,3075)","0","mstr_standard","I213";
;
CDS_LIB"mstr_standard"
BODY_TYPE"PLUMBING"
HDL_TAP"TRUE";
"B \NAC \NWC"2;
"S \NAC"
BN"20"120;
%"TAP"
"1","(-3375,3125)","0","mstr_standard","I214";
;
CDS_LIB"mstr_standard"
BODY_TYPE"PLUMBING"
HDL_TAP"TRUE";
"B \NAC \NWC"2;
"S \NAC"
BN"19"124;
%"TAP"
"1","(-3375,3175)","0","mstr_standard","I215";
;
CDS_LIB"mstr_standard"
BODY_TYPE"PLUMBING"
HDL_TAP"TRUE";
"B \NAC \NWC"2;
"S \NAC"
BN"18"107;
%"TAP"
"1","(-3375,2975)","0","mstr_standard","I216";
;
CDS_LIB"mstr_standard"
BODY_TYPE"PLUMBING"
HDL_TAP"TRUE";
"B \NAC \NWC"2;
"S \NAC"
BN"22"95;
%"TAP"
"1","(-3375,3025)","0","mstr_standard","I217";
;
CDS_LIB"mstr_standard"
BODY_TYPE"PLUMBING"
HDL_TAP"TRUE";
"B \NAC \NWC"2;
"S \NAC"
BN"21"96;
%"TAP"
"1","(-3375,2825)","0","mstr_standard","I218";
;
CDS_LIB"mstr_standard"
BODY_TYPE"PLUMBING"
HDL_TAP"TRUE";
"B \NAC \NWC"2;
"S \NAC"
BN"24"93;
%"TAP"
"1","(-3375,2925)","0","mstr_standard","I219";
;
CDS_LIB"mstr_standard"
BODY_TYPE"PLUMBING"
HDL_TAP"TRUE";
"B \NAC \NWC"2;
"S \NAC"
BN"23"94;
%"TAP"
"1","(-3375,2775)","0","mstr_standard","I220";
;
CDS_LIB"mstr_standard"
BODY_TYPE"PLUMBING"
HDL_TAP"TRUE";
"B \NAC \NWC"2;
"S \NAC"
BN"25"92;
%"TAP"
"1","(-3375,2725)","0","mstr_standard","I221";
;
CDS_LIB"mstr_standard"
BODY_TYPE"PLUMBING"
HDL_TAP"TRUE";
"B \NAC \NWC"2;
"S \NAC"
BN"26"91;
%"TAP"
"1","(-3375,2575)","0","mstr_standard","I222";
;
CDS_LIB"mstr_standard"
BODY_TYPE"PLUMBING"
HDL_TAP"TRUE";
"B \NAC \NWC"2;
"S \NAC"
BN"29"88;
%"TAP"
"1","(-3375,2625)","0","mstr_standard","I223";
;
CDS_LIB"mstr_standard"
BODY_TYPE"PLUMBING"
HDL_TAP"TRUE";
"B \NAC \NWC"2;
"S \NAC"
BN"28"89;
%"TAP"
"1","(-3375,2675)","0","mstr_standard","I224";
;
CDS_LIB"mstr_standard"
BODY_TYPE"PLUMBING"
HDL_TAP"TRUE";
"B \NAC \NWC"2;
"S \NAC"
BN"27"90;
%"TAP"
"1","(-3375,2525)","0","mstr_standard","I225";
;
CDS_LIB"mstr_standard"
BODY_TYPE"PLUMBING"
HDL_TAP"TRUE";
"B \NAC \NWC"2;
"S \NAC"
BN"30"100;
%"TAP"
"1","(-3375,2475)","0","mstr_standard","I226";
;
CDS_LIB"mstr_standard"
BODY_TYPE"PLUMBING"
HDL_TAP"TRUE";
"B \NAC \NWC"2;
"S \NAC"
BN"31"98;
%"TAP"
"1","(-3375,2325)","0","mstr_standard","I227";
;
CDS_LIB"mstr_standard"
BODY_TYPE"PLUMBING"
HDL_TAP"TRUE";
"B \NAC \NWC"3;
"S \NAC"
BN"1"104;
%"TAP"
"1","(-3375,2375)","0","mstr_standard","I228";
;
CDS_LIB"mstr_standard"
BODY_TYPE"PLUMBING"
HDL_TAP"TRUE";
"B \NAC \NWC"3;
"S \NAC"
BN"0"105;
%"TAP"
"1","(-3375,2275)","0","mstr_standard","I229";
;
CDS_LIB"mstr_standard"
BODY_TYPE"PLUMBING"
HDL_TAP"TRUE";
"B \NAC \NWC"3;
"S \NAC"
BN"2"103;
%"TAP"
"1","(-3375,2225)","0","mstr_standard","I230";
;
CDS_LIB"mstr_standard"
BODY_TYPE"PLUMBING"
HDL_TAP"TRUE";
"B \NAC \NWC"3;
"S \NAC"
BN"3"102;
%"TAP"
"1","(-3375,2075)","0","mstr_standard","I231";
;
CDS_LIB"mstr_standard"
BODY_TYPE"PLUMBING"
HDL_TAP"TRUE";
"B \NAC \NWC"3;
"S \NAC"
BN"6"97;
%"TAP"
"1","(-3375,2125)","0","mstr_standard","I232";
;
CDS_LIB"mstr_standard"
BODY_TYPE"PLUMBING"
HDL_TAP"TRUE";
"B \NAC \NWC"3;
"S \NAC"
BN"5"99;
%"TAP"
"1","(-3375,2175)","0","mstr_standard","I233";
;
CDS_LIB"mstr_standard"
BODY_TYPE"PLUMBING"
HDL_TAP"TRUE";
"B \NAC \NWC"3;
"S \NAC"
BN"4"101;
%"TAP"
"1","(-3375,2025)","0","mstr_standard","I235";
;
CDS_LIB"mstr_standard"
BODY_TYPE"PLUMBING"
HDL_TAP"TRUE";
"B \NAC \NWC"3;
"S \NAC"
BN"7"85;
%"TAP"
"1","(-3375,1925)","0","mstr_standard","I236";
;
CDS_LIB"mstr_standard"
BODY_TYPE"PLUMBING"
HDL_TAP"TRUE";
"B \NAC \NWC"4;
"S \NAC"
BN"0"87;
%"TAP"
"1","(-3375,1825)","0","mstr_standard","I237";
;
CDS_LIB"mstr_standard"
BODY_TYPE"PLUMBING"
HDL_TAP"TRUE";
"B \NAC \NWC"4;
"S \NAC"
BN"2"84;
%"TAP"
"1","(-3375,1875)","0","mstr_standard","I238";
;
CDS_LIB"mstr_standard"
BODY_TYPE"PLUMBING"
HDL_TAP"TRUE";
"B \NAC \NWC"4;
"S \NAC"
BN"1"86;
%"TAP"
"1","(-3375,1675)","0","mstr_standard","I239";
;
CDS_LIB"mstr_standard"
BODY_TYPE"PLUMBING"
HDL_TAP"TRUE";
"B \NAC \NWC"4;
"S \NAC"
BN"5"81;
%"TAP"
"1","(-3375,1725)","0","mstr_standard","I240";
;
CDS_LIB"mstr_standard"
BODY_TYPE"PLUMBING"
HDL_TAP"TRUE";
"B \NAC \NWC"4;
"S \NAC"
BN"4"82;
%"TAP"
"1","(-3375,1775)","0","mstr_standard","I241";
;
CDS_LIB"mstr_standard"
BODY_TYPE"PLUMBING"
HDL_TAP"TRUE";
"B \NAC \NWC"4;
"S \NAC"
BN"3"83;
%"TAP"
"1","(-3375,1575)","0","mstr_standard","I242";
;
CDS_LIB"mstr_standard"
BODY_TYPE"PLUMBING"
HDL_TAP"TRUE";
"B \NAC \NWC"4;
"S \NAC"
BN"7"79;
%"TAP"
"1","(-3375,1625)","0","mstr_standard","I243";
;
CDS_LIB"mstr_standard"
BODY_TYPE"PLUMBING"
HDL_TAP"TRUE";
"B \NAC \NWC"4;
"S \NAC"
BN"6"80;
%"TAP"
"1","(-5800,5975)","2","mstr_standard","I244";
;
CDS_LIB"mstr_standard"
BODY_TYPE"PLUMBING"
HDL_TAP"TRUE";
"B \NAC \NWC"5;
"S \NAC"
BN"0"72;
%"TAP"
"1","(-5800,5875)","2","mstr_standard","I245";
;
CDS_LIB"mstr_standard"
BODY_TYPE"PLUMBING"
HDL_TAP"TRUE";
"B \NAC \NWC"5;
"S \NAC"
BN"1"70;
%"TAP"
"1","(-5800,5775)","2","mstr_standard","I246";
;
CDS_LIB"mstr_standard"
BODY_TYPE"PLUMBING"
HDL_TAP"TRUE";
"B \NAC \NWC"5;
"S \NAC"
BN"2"68;
%"TAP"
"1","(-5800,5675)","2","mstr_standard","I247";
;
CDS_LIB"mstr_standard"
BODY_TYPE"PLUMBING"
HDL_TAP"TRUE";
"B \NAC \NWC"5;
"S \NAC"
BN"3"66;
%"TAP"
"1","(-6000,5925)","2","mstr_standard","I248";
;
CDS_LIB"mstr_standard"
BODY_TYPE"PLUMBING"
HDL_TAP"TRUE";
"B \NAC \NWC"9;
"S \NAC"
BN"0"77;
%"TAP"
"1","(-6000,5825)","2","mstr_standard","I249";
;
CDS_LIB"mstr_standard"
BODY_TYPE"PLUMBING"
HDL_TAP"TRUE";
"B \NAC \NWC"9;
"S \NAC"
BN"1"76;
%"TAP"
"1","(-6000,5725)","2","mstr_standard","I250";
;
CDS_LIB"mstr_standard"
BODY_TYPE"PLUMBING"
HDL_TAP"TRUE";
"B \NAC \NWC"9;
"S \NAC"
BN"2"75;
%"TAP"
"1","(-5800,5575)","2","mstr_standard","I251";
;
CDS_LIB"mstr_standard"
BODY_TYPE"PLUMBING"
HDL_TAP"TRUE";
"B \NAC \NWC"5;
"S \NAC"
BN"4"64;
%"TAP"
"1","(-5800,5475)","2","mstr_standard","I252";
;
CDS_LIB"mstr_standard"
BODY_TYPE"PLUMBING"
HDL_TAP"TRUE";
"B \NAC \NWC"5;
"S \NAC"
BN"5"63;
%"TAP"
"1","(-5800,5375)","2","mstr_standard","I253";
;
CDS_LIB"mstr_standard"
BODY_TYPE"PLUMBING"
HDL_TAP"TRUE";
"B \NAC \NWC"5;
"S \NAC"
BN"6"62;
%"TAP"
"1","(-5800,5275)","2","mstr_standard","I254";
;
CDS_LIB"mstr_standard"
BODY_TYPE"PLUMBING"
HDL_TAP"TRUE";
"B \NAC \NWC"5;
"S \NAC"
BN"7"61;
%"TAP"
"1","(-5800,5175)","2","mstr_standard","I255";
;
CDS_LIB"mstr_standard"
BODY_TYPE"PLUMBING"
HDL_TAP"TRUE";
"B \NAC \NWC"5;
"S \NAC"
BN"8"78;
%"TAP"
"1","(-6000,5625)","2","mstr_standard","I256";
;
CDS_LIB"mstr_standard"
BODY_TYPE"PLUMBING"
HDL_TAP"TRUE";
"B \NAC \NWC"9;
"S \NAC"
BN"3"74;
%"TAP"
"1","(-6000,5525)","2","mstr_standard","I257";
;
CDS_LIB"mstr_standard"
BODY_TYPE"PLUMBING"
HDL_TAP"TRUE";
"B \NAC \NWC"9;
"S \NAC"
BN"4"73;
%"TAP"
"1","(-6000,5425)","2","mstr_standard","I258";
;
CDS_LIB"mstr_standard"
BODY_TYPE"PLUMBING"
HDL_TAP"TRUE";
"B \NAC \NWC"9;
"S \NAC"
BN"5"71;
%"TAP"
"1","(-6000,5325)","2","mstr_standard","I259";
;
CDS_LIB"mstr_standard"
BODY_TYPE"PLUMBING"
HDL_TAP"TRUE";
"B \NAC \NWC"9;
"S \NAC"
BN"6"69;
%"TAP"
"1","(-6000,5125)","2","mstr_standard","I260";
;
CDS_LIB"mstr_standard"
BODY_TYPE"PLUMBING"
HDL_TAP"TRUE";
"B \NAC \NWC"9;
"S \NAC"
BN"8"65;
%"TAP"
"1","(-6000,5225)","2","mstr_standard","I261";
;
CDS_LIB"mstr_standard"
BODY_TYPE"PLUMBING"
HDL_TAP"TRUE";
"B \NAC \NWC"9;
"S \NAC"
BN"7"67;
%"TAP"
"1","(-5800,5075)","2","mstr_standard","I262";
;
CDS_LIB"mstr_standard"
BODY_TYPE"PLUMBING"
HDL_TAP"TRUE";
"B \NAC \NWC"5;
"S \NAC"
BN"9"56;
%"TAP"
"1","(-5800,4925)","2","mstr_standard","I263";
;
CDS_LIB"mstr_standard"
BODY_TYPE"PLUMBING"
HDL_TAP"TRUE";
"B \NAC \NWC"6;
"S \NAC"
BN"0"44;
%"TAP"
"1","(-5800,4825)","2","mstr_standard","I264";
;
CDS_LIB"mstr_standard"
BODY_TYPE"PLUMBING"
HDL_TAP"TRUE";
"B \NAC \NWC"6;
"S \NAC"
BN"1"42;
%"TAP"
"1","(-5800,4725)","2","mstr_standard","I265";
;
CDS_LIB"mstr_standard"
BODY_TYPE"PLUMBING"
HDL_TAP"TRUE";
"B \NAC \NWC"6;
"S \NAC"
BN"2"59;
%"TAP"
"1","(-5800,4625)","2","mstr_standard","I266";
;
CDS_LIB"mstr_standard"
BODY_TYPE"PLUMBING"
HDL_TAP"TRUE";
"B \NAC \NWC"6;
"S \NAC"
BN"3"57;
%"TAP"
"1","(-6000,5025)","2","mstr_standard","I267";
;
CDS_LIB"mstr_standard"
BODY_TYPE"PLUMBING"
HDL_TAP"TRUE";
"B \NAC \NWC"9;
"S \NAC"
BN"9"46;
%"TAP"
"1","(-6000,4875)","2","mstr_standard","I268";
;
CDS_LIB"mstr_standard"
BODY_TYPE"PLUMBING"
HDL_TAP"TRUE";
"B \NAC \NWC"10;
"S \NAC"
BN"0"50;
%"TAP"
"1","(-6000,4775)","2","mstr_standard","I269";
;
CDS_LIB"mstr_standard"
BODY_TYPE"PLUMBING"
HDL_TAP"TRUE";
"B \NAC \NWC"10;
"S \NAC"
BN"1"49;
%"TAP"
"1","(-6000,4675)","2","mstr_standard","I270";
;
CDS_LIB"mstr_standard"
BODY_TYPE"PLUMBING"
HDL_TAP"TRUE";
"B \NAC \NWC"10;
"S \NAC"
BN"2"48;
%"TAP"
"1","(-5800,4525)","2","mstr_standard","I271";
;
CDS_LIB"mstr_standard"
BODY_TYPE"PLUMBING"
HDL_TAP"TRUE";
"B \NAC \NWC"6;
"S \NAC"
BN"4"55;
%"TAP"
"1","(-5800,4425)","2","mstr_standard","I272";
;
CDS_LIB"mstr_standard"
BODY_TYPE"PLUMBING"
HDL_TAP"TRUE";
"B \NAC \NWC"6;
"S \NAC"
BN"5"54;
%"TAP"
"1","(-5800,4325)","2","mstr_standard","I273";
;
CDS_LIB"mstr_standard"
BODY_TYPE"PLUMBING"
HDL_TAP"TRUE";
"B \NAC \NWC"6;
"S \NAC"
BN"6"53;
%"TAP"
"1","(-5800,4225)","2","mstr_standard","I274";
;
CDS_LIB"mstr_standard"
BODY_TYPE"PLUMBING"
HDL_TAP"TRUE";
"B \NAC \NWC"6;
"S \NAC"
BN"7"52;
%"TAP"
"1","(-5800,4125)","2","mstr_standard","I275";
;
CDS_LIB"mstr_standard"
BODY_TYPE"PLUMBING"
HDL_TAP"TRUE";
"B \NAC \NWC"6;
"S \NAC"
BN"8"51;
%"TAP"
"1","(-6000,4575)","2","mstr_standard","I276";
;
CDS_LIB"mstr_standard"
BODY_TYPE"PLUMBING"
HDL_TAP"TRUE";
"B \NAC \NWC"10;
"S \NAC"
BN"3"47;
%"TAP"
"1","(-6000,4475)","2","mstr_standard","I277";
;
CDS_LIB"mstr_standard"
BODY_TYPE"PLUMBING"
HDL_TAP"TRUE";
"B \NAC \NWC"10;
"S \NAC"
BN"4"45;
%"TAP"
"1","(-6000,4375)","2","mstr_standard","I278";
;
CDS_LIB"mstr_standard"
BODY_TYPE"PLUMBING"
HDL_TAP"TRUE";
"B \NAC \NWC"10;
"S \NAC"
BN"5"43;
%"TAP"
"1","(-6000,4275)","2","mstr_standard","I279";
;
CDS_LIB"mstr_standard"
BODY_TYPE"PLUMBING"
HDL_TAP"TRUE";
"B \NAC \NWC"10;
"S \NAC"
BN"6"60;
%"TAP"
"1","(-6000,4175)","2","mstr_standard","I280";
;
CDS_LIB"mstr_standard"
BODY_TYPE"PLUMBING"
HDL_TAP"TRUE";
"B \NAC \NWC"10;
"S \NAC"
BN"7"58;
%"TAP"
"1","(-5800,4025)","2","mstr_standard","I285";
;
CDS_LIB"mstr_standard"
BODY_TYPE"PLUMBING"
HDL_TAP"TRUE";
"B \NAC \NWC"6;
"S \NAC"
BN"9"25;
%"TAP"
"1","(-6000,3975)","2","mstr_standard","I286";
;
CDS_LIB"mstr_standard"
BODY_TYPE"PLUMBING"
HDL_TAP"TRUE";
"B \NAC \NWC"10;
"S \NAC"
BN"9"40;
%"TAP"
"1","(-6000,4075)","2","mstr_standard","I287";
;
CDS_LIB"mstr_standard"
BODY_TYPE"PLUMBING"
HDL_TAP"TRUE";
"B \NAC \NWC"10;
"S \NAC"
BN"8"41;
%"TAP"
"1","(-6000,3825)","2","mstr_standard","I288";
;
CDS_LIB"mstr_standard"
BODY_TYPE"PLUMBING"
HDL_TAP"TRUE";
"B \NAC \NWC"7;
"S \NAC"
BN"0"39;
%"TAP"
"1","(-6000,3775)","2","mstr_standard","I289";
;
CDS_LIB"mstr_standard"
BODY_TYPE"PLUMBING"
HDL_TAP"TRUE";
"B \NAC \NWC"7;
"S \NAC"
BN"1"37;
%"TAP"
"1","(-6000,3725)","2","mstr_standard","I290";
;
CDS_LIB"mstr_standard"
BODY_TYPE"PLUMBING"
HDL_TAP"TRUE";
"B \NAC \NWC"7;
"S \NAC"
BN"2"35;
%"TAP"
"1","(-6000,3675)","2","mstr_standard","I291";
;
CDS_LIB"mstr_standard"
BODY_TYPE"PLUMBING"
HDL_TAP"TRUE";
"B \NAC \NWC"7;
"S \NAC"
BN"3"33;
%"TAP"
"1","(-6000,3625)","2","mstr_standard","I292";
;
CDS_LIB"mstr_standard"
BODY_TYPE"PLUMBING"
HDL_TAP"TRUE";
"B \NAC \NWC"7;
"S \NAC"
BN"4"31;
%"TAP"
"1","(-6000,3575)","2","mstr_standard","I293";
;
CDS_LIB"mstr_standard"
BODY_TYPE"PLUMBING"
HDL_TAP"TRUE";
"B \NAC \NWC"7;
"S \NAC"
BN"5"29;
%"TAP"
"1","(-6000,3525)","2","mstr_standard","I294";
;
CDS_LIB"mstr_standard"
BODY_TYPE"PLUMBING"
HDL_TAP"TRUE";
"B \NAC \NWC"7;
"S \NAC"
BN"6"27;
%"TAP"
"1","(-6000,3425)","2","mstr_standard","I295";
;
CDS_LIB"mstr_standard"
BODY_TYPE"PLUMBING"
HDL_TAP"TRUE";
"B \NAC \NWC"8;
"S \NAC"
BN"0"38;
%"TAP"
"1","(-6000,3375)","2","mstr_standard","I296";
;
CDS_LIB"mstr_standard"
BODY_TYPE"PLUMBING"
HDL_TAP"TRUE";
"B \NAC \NWC"8;
"S \NAC"
BN"1"36;
%"TAP"
"1","(-6000,3325)","2","mstr_standard","I297";
;
CDS_LIB"mstr_standard"
BODY_TYPE"PLUMBING"
HDL_TAP"TRUE";
"B \NAC \NWC"8;
"S \NAC"
BN"2"34;
%"TAP"
"1","(-6000,3275)","2","mstr_standard","I298";
;
CDS_LIB"mstr_standard"
BODY_TYPE"PLUMBING"
HDL_TAP"TRUE";
"B \NAC \NWC"8;
"S \NAC"
BN"3"32;
%"TAP"
"1","(-6000,3225)","2","mstr_standard","I299";
;
CDS_LIB"mstr_standard"
BODY_TYPE"PLUMBING"
HDL_TAP"TRUE";
"B \NAC \NWC"8;
"S \NAC"
BN"4"30;
%"TAP"
"1","(-6000,3125)","2","mstr_standard","I300";
;
CDS_LIB"mstr_standard"
BODY_TYPE"PLUMBING"
HDL_TAP"TRUE";
"B \NAC \NWC"8;
"S \NAC"
BN"6"26;
%"TAP"
"1","(-6000,3175)","2","mstr_standard","I301";
;
CDS_LIB"mstr_standard"
BODY_TYPE"PLUMBING"
HDL_TAP"TRUE";
"B \NAC \NWC"8;
"S \NAC"
BN"5"28;
%"Q_RES"
"1","(-6925,2125)","0","pure_quanta","I314";
;
LOCATION"R380"
$SEC"1"
CDS_SEC"1"
TOLERANCE"1%"
VALUE"15   "
PART_NUMBER"CS01502FB11"
PACK_TYPE"0402LF"
CDS_LIB"pure_quanta"
WATTAGE"1/16W"
MATERIAL"CHIP";
"B"
$PN"2"13;
"A"
$PN"1"11;
END.
